# T6G (Grand Teton) — schematic netlist excerpt (pin names and nets, part order shuffled) for the footprints in the layout excerpt that follows; sources: Cadence DE-HDL packaged netlist, KiCad conversion of 04192023_DAF0TMB3IC0_F0TG_MB_C_brd_V02_OCP.brd

C443  Q_CAP  0.1UF 10V 10% X7S  pkg C0201  page 356 : A = P1V8_CPU1_RT3_1A ; B = GND
C1922  Q_CAP  22UF 4V 20% X6S  pkg C0402  page 69 : A = PVDDCR_CPU0_P0 ; B = GND
C355  Q_CAP  0.1UF 16V 10% X7R  pkg C0402  page 83 : A = P3V3_AUX ; B = GND

(kicad_pcb
	(version 20260206)
	(generator "pcbnew")
	(generator_version "10.0")
	(general
		(thickness 1.6)
		(legacy_teardrops no)
	)
	(paper "A4")
	(title_block
		(title "04192023_DAF0TMB3IC0_F0TG_MB_C_brd_V02_OCP.brd")
		(comment 1 "Grand Teton / footprints 5437-5439 of 8354")
	)
	(layers
		(0 "F.Cu" signal "TOP")
		(4 "In1.Cu" signal "GND")
		(6 "In2.Cu" signal "IN1")
		(8 "In3.Cu" signal "GND1")
		(10 "In4.Cu" signal "IN2")
		(12 "In5.Cu" signal "GND2")
		(14 "In6.Cu" signal "IN3")
		(16 "In7.Cu" signal "GND3")
		(18 "In8.Cu" signal "VCC")
		(20 "In9.Cu" signal "VCC1")
		(22 "In10.Cu" signal "GND4")
		(24 "In11.Cu" signal "IN4")
		(26 "In12.Cu" signal "GND5")
		(28 "In13.Cu" signal "IN5")
		(30 "In14.Cu" signal "GND6")
		(32 "In15.Cu" signal "IN6")
		(34 "In16.Cu" signal "GND7")
		(2 "B.Cu" signal "BOTTOM")
		(9 "F.Adhes" user "F.Adhesive")
		(11 "B.Adhes" user "B.Adhesive")
		(13 "F.Paste" user "Package Geometry/Pastemask Top")
		(15 "B.Paste" user "Package Geometry/Pastemask Bottom")
		(5 "F.SilkS" user "Ref Des/Silkscreen Top")
		(7 "B.SilkS" user "Ref Des/Silkscreen Bottom")
		(1 "F.Mask" user "Board Geometry/Soldermask Top")
		(3 "B.Mask" user "Board Geometry/Soldermask Bottom")
		(17 "Dwgs.User" user "User.Drawings")
		(19 "Cmts.User" user "User.Comments")
		(21 "Eco1.User" user "User.Eco1")
		(23 "Eco2.User" user "User.Eco2")
		(25 "Edge.Cuts" user "Board Geometry/Outline")
		(27 "Margin" user)
		(31 "F.CrtYd" user "Package Geometry/Place Bound Top")
		(29 "B.CrtYd" user "Package Geometry/Place Bound Bottom")
		(35 "F.Fab" user "Ref Des/Assembly Top")
		(33 "B.Fab" user "Ref Des/Assembly Bottom")
	)
	(footprint ""
		(layer "B.Cu")
		(at 350.818958 -249.36831 180)
		(property "Reference" "C1922"
			(at 0 0 0)
			(layer "B.SilkS")
			(hide yes)
			(effects
				(font
					(size 1.27 1.27)
				)
				(justify mirror)
			)
		)
		(property "Value" ""
			(at 0 0 0)
			(layer "B.Fab")
			(effects
				(font
					(size 1.27 1.27)
				)
				(justify mirror)
			)
		)
		(duplicate_pad_numbers_are_jumpers no)
		(fp_line
			(start 0.7874 0.4064)
			(end 0.7874 -0.4064)
			(stroke
				(width 0.1524)
				(type default)
			)
			(layer "B.SilkS")
		)
		(fp_line
			(start 0.7874 -0.4064)
			(end -0.7874 -0.4064)
			(stroke
				(width 0.1524)
				(type default)
			)
			(layer "B.SilkS")
		)
		(fp_line
			(start -0.7874 0.4064)
			(end 0.7874 0.4064)
			(stroke
				(width 0.1524)
				(type default)
			)
			(layer "B.SilkS")
		)
		(fp_line
			(start -0.7874 -0.4064)
			(end -0.7874 0.4064)
			(stroke
				(width 0.1524)
				(type default)
			)
			(layer "B.SilkS")
		)
		(fp_line
			(start 0.67945 0.3048)
			(end 0.67945 -0.305054)
			(stroke
				(width 0.1)
				(type default)
			)
			(layer "B.Fab")
		)
		(fp_line
			(start 0.67945 -0.305054)
			(end 0.12065 -0.305054)
			(stroke
				(width 0.1)
				(type default)
			)
			(layer "B.Fab")
		)
		(fp_line
			(start 0.12065 0.3048)
			(end 0.67945 0.3048)
			(stroke
				(width 0.1)
				(type default)
			)
			(layer "B.Fab")
		)
		(fp_line
			(start 0.12065 0.2794)
			(end 0.12065 0.3048)
			(stroke
				(width 0.1)
				(type default)
			)
			(layer "B.Fab")
		)
		(fp_line
			(start 0.12065 -0.2794)
			(end -0.12065 -0.2794)
			(stroke
				(width 0.1)
				(type default)
			)
			(layer "B.Fab")
		)
		(fp_line
			(start 0.12065 -0.305054)
			(end 0.12065 -0.2794)
			(stroke
				(width 0.1)
				(type default)
			)
			(layer "B.Fab")
		)
		(fp_line
			(start -0.120396 0.3048)
			(end -0.120396 0.2794)
			(stroke
				(width 0.1)
				(type default)
			)
			(layer "B.Fab")
		)
		(fp_line
			(start -0.120396 0.2794)
			(end 0.12065 0.2794)
			(stroke
				(width 0.1)
				(type default)
			)
			(layer "B.Fab")
		)
		(fp_line
			(start -0.12065 -0.2794)
			(end -0.12065 -0.3048)
			(stroke
				(width 0.1)
				(type default)
			)
			(layer "B.Fab")
		)
		(fp_line
			(start -0.12065 -0.3048)
			(end -0.67945 -0.3048)
			(stroke
				(width 0.1)
				(type default)
			)
			(layer "B.Fab")
		)
		(fp_line
			(start -0.67945 0.3048)
			(end -0.120396 0.3048)
			(stroke
				(width 0.1)
				(type default)
			)
			(layer "B.Fab")
		)
		(fp_line
			(start -0.67945 -0.3048)
			(end -0.67945 0.3048)
			(stroke
				(width 0.1)
				(type default)
			)
			(layer "B.Fab")
		)
		(pad "1" smd circle
			(at 0.40005 0)
			(size 0 0)
			(layers "B.Cu" "B.Mask" "B.Paste")
			(net "PVDDCR_CPU0_P0")
		)
		(pad "2" smd circle
			(at -0.40005 0)
			(size 0 0)
			(layers "B.Cu" "B.Mask" "B.Paste")
			(net "GND")
		)
	)
	(footprint ""
		(layer "B.Cu")
		(at 122.878596 -386.766562 90)
		(property "Reference" "C443"
			(at 0 0 90)
			(layer "B.SilkS")
			(hide yes)
			(effects
				(font
					(size 1.27 1.27)
				)
				(justify mirror)
			)
		)
		(property "Value" ""
			(at 0 0 90)
			(layer "B.Fab")
			(effects
				(font
					(size 1.27 1.27)
				)
				(justify mirror)
			)
		)
		(duplicate_pad_numbers_are_jumpers no)
		(fp_line
			(start 0.299974 -0.150114)
			(end -0.299974 -0.150114)
			(stroke
				(width 0.1)
				(type default)
			)
			(layer "B.Fab")
		)
		(fp_line
			(start -0.299974 -0.150114)
			(end -0.299974 0.150114)
			(stroke
				(width 0.1)
				(type default)
			)
			(layer "B.Fab")
		)
		(fp_line
			(start 0.299974 0.150114)
			(end 0.299974 -0.150114)
			(stroke
				(width 0.1)
				(type default)
			)
			(layer "B.Fab")
		)
		(fp_line
			(start -0.299974 0.150114)
			(end 0.299974 0.150114)
			(stroke
				(width 0.1)
				(type default)
			)
			(layer "B.Fab")
		)
		(pad "1" smd rect
			(at 0.2667 0 270)
			(size 0.3048 0.381)
			(layers "B.Cu" "B.Mask" "B.Paste")
			(net "P1V8_CPU1_RT3_1A")
		)
		(pad "2" smd rect
			(at -0.2667 0 270)
			(size 0.3048 0.381)
			(layers "B.Cu" "B.Mask" "B.Paste")
			(net "GND")
		)
	)
	(footprint ""
		(layer "B.Cu")
		(at 182.332376 -115.022376 180)
		(property "Reference" "C355"
			(at 0 0 0)
			(layer "B.SilkS")
			(hide yes)
			(effects
				(font
					(size 1.27 1.27)
				)
				(justify mirror)
			)
		)
		(property "Value" ""
			(at 0 0 0)
			(layer "B.Fab")
			(effects
				(font
					(size 1.27 1.27)
				)
				(justify mirror)
			)
		)
		(duplicate_pad_numbers_are_jumpers no)
		(fp_line
			(start 0.69215 0.2921)
			(end 0.69215 -0.2921)
			(stroke
				(width 0.1524)
				(type default)
			)
			(layer "B.SilkS")
		)
		(fp_line
			(start 0.69215 -0.2921)
			(end -0.69215 -0.2921)
			(stroke
				(width 0.1524)
				(type default)
			)
			(layer "B.SilkS")
		)
		(fp_line
			(start -0.69215 0.2921)
			(end 0.69215 0.2921)
			(stroke
				(width 0.1524)
				(type default)
			)
			(layer "B.SilkS")
		)
		(fp_line
			(start -0.69215 -0.2921)
			(end -0.69215 0.2921)
			(stroke
				(width 0.1524)
				(type default)
			)
			(layer "B.SilkS")
		)
		(fp_line
			(start 0.51435 0.2794)
			(end 0.51435 -0.2794)
			(stroke
				(width 0.1)
				(type default)
			)
			(layer "B.Fab")
		)
		(fp_line
			(start 0.51435 -0.2794)
			(end -0.51435 -0.2794)
			(stroke
				(width 0.1)
				(type default)
			)
			(layer "B.Fab")
		)
		(fp_line
			(start -0.51435 0.2794)
			(end 0.51435 0.2794)
			(stroke
				(width 0.1)
				(type default)
			)
			(layer "B.Fab")
		)
		(fp_line
			(start -0.51435 -0.2794)
			(end -0.51435 0.2794)
			(stroke
				(width 0.1)
				(type default)
			)
			(layer "B.Fab")
		)
		(pad "1" smd circle
			(at 0.40005 0)
			(size 0 0)
			(layers "B.Cu" "B.Mask" "B.Paste")
			(net "P3V3_AUX")
		)
		(pad "2" smd circle
			(at -0.40005 0)
			(size 0 0)
			(layers "B.Cu" "B.Mask" "B.Paste")
			(net "GND")
		)
		(zone
			(layer "B.Cu")
			(hatch none 0.5)
			(connect_pads
				(clearance 0)
			)
			(min_thickness 0.25)
			(keepout
				(tracks not_allowed)
				(vias allowed)
				(pads allowed)
				(copperpour not_allowed)
				(footprints allowed)
			)
			(placement
				(enabled no)
				(sheetname "")
			)
			(fill
				(thermal_gap 0.5)
				(thermal_bridge_width 0.5)
				(island_removal_mode 0)
			)
			(polygon
				(pts
					(xy 182.141876 -114.934492) (xy 182.141876 -115.110006) (xy 182.233316 -115.168172) (xy 182.432706 -115.168172)
					(xy 182.522876 -115.110006) (xy 182.522876 -114.934746) (xy 182.432706 -114.876326) (xy 182.233316 -114.876326)
				)
			)
		)
	)
)
